FILE_TYPE = CONNECTIVITY;
{Allegro Design Entry HDL 17.2-2016 S081 (4005846) 1/11/2022}
"PAGE_NUMBER" = 130;
0"NC";
1"PVCCD_HV_CPU1\g";
2"PVCCD_HV_CPU1\g";
3"PVCCD_HV_CPU1\g";
4"PVCCD_HV_CPU1\g";
5"GND\g";
6"GND\g";
7"GND\g";
8"GND\g";
9"RST_M_GH_CPU1_FPGA_N";
10"RST_PLD_CPU1_DRAM_EF_N";
11"RST_M_AB_CPU1_FPGA_N";
12"RST_M_EF_CPU1_FPGA_N";
13"RST_M_CD_CPU1_FPGA_N";
14"RST_PLD_CPU1_DRAM_AB_N";
15"RST_PLD_CPU1_DRAM_GH_N";
16"RST_PLD_CPU1_DRAM_CD_N";
%"Q_RES"
"1","(-5200,-350)","0","pure_quanta","I11";
;
PART_NUMBER"CS00002JB13"
PACK_TYPE"0402LF"
TOLERANCE"5%"
VALUE"0"
MATERIAL"CHIP"
WATTAGE"1/16W"
$LOCATION"R815"
CDS_LIB"pure_quanta"
$LOCATION"R815"
CDS_LOCATION"R815"
$SEC"1"
CDS_SEC"1";
"B"
$PN"2"9;
"A"
$PN"1"15;
%"Q_RES"
"1","(-5175,1175)","0","pure_quanta","I22";
;
PART_NUMBER"CS00002JB13"
TOLERANCE"5%"
VALUE"0"
PACK_TYPE"0402LF"
WATTAGE"1/16W"
MATERIAL"CHIP"
$LOCATION"R818"
CDS_LIB"pure_quanta"
$LOCATION"R818"
CDS_LOCATION"R818"
$SEC"1"
CDS_SEC"1";
"B"
$PN"2"12;
"A"
$PN"1"10;
%"Q_RES"
"1","(-5175,2675)","0","pure_quanta","I26";
;
PART_NUMBER"CS00002JB13"
MATERIAL"CHIP"
WATTAGE"1/16W"
PACK_TYPE"0402LF"
TOLERANCE"5%"
VALUE"0"
$LOCATION"R817"
CDS_LIB"pure_quanta"
$LOCATION"R817"
CDS_LOCATION"R817"
$SEC"1"
CDS_SEC"1";
"B"
$PN"2"13;
"A"
$PN"1"16;
%"Q_RES"
"1","(-5175,4200)","0","pure_quanta","I37";
;
PART_NUMBER"CS00002JB13"
MATERIAL"CHIP"
VALUE"0"
TOLERANCE"5%"
WATTAGE"1/16W"
PACK_TYPE"0402LF"
$LOCATION"R816"
CDS_LIB"pure_quanta"
$LOCATION"R816"
CDS_LOCATION"R816"
$SEC"1"
CDS_SEC"1";
"B"
$PN"2"11;
"A"
$PN"1"14;
%"UNIVERSAL_GND"
"1","(-7750,-950)","0","logical_power","I57";
;
CDS_LIB"logical_power"
HDL_POWER"GND";
"A"8;
%"UNIVERSAL_GND"
"1","(-7725,575)","0","logical_power","I58";
;
CDS_LIB"logical_power"
HDL_POWER"GND";
"A"7;
%"Q_CAP"
"1","(-7725,875)","2","pure_quanta","I59";
;
PART_NUMBER"CH5104KEB02"
VALUE"1UF"
VOLTAGE"25V"
TOLERANCE"10%"
PACK_TYPE"C0402"
MATERIAL"EMPTY"
$LOCATION"C616"
CDS_LIB"pure_quanta"
CDS_LOCATION"C616"
$SEC"1"
CDS_SEC"1";
"B"
$PN"2"7;
"A"
$PN"1"10;
%"UNIVERSAL_GND"
"1","(-7725,2075)","0","logical_power","I61";
;
CDS_LIB"logical_power"
HDL_POWER"GND";
"A"6;
%"Q_CAP"
"1","(-7725,2375)","2","pure_quanta","I62";
;
PART_NUMBER"CH5104KEB02"
PACK_TYPE"C0402"
VOLTAGE"25V"
VALUE"1UF"
TOLERANCE"10%"
MATERIAL"EMPTY"
$LOCATION"C615"
CDS_LIB"pure_quanta"
CDS_LOCATION"C615"
$SEC"1"
CDS_SEC"1";
"B"
$PN"2"6;
"A"
$PN"1"16;
%"Q_RES"
"2","(-7625,2400)","0","pure_quanta","I63";
;
PART_NUMBER"CS31002FB08"
VALUE"10K"
TOLERANCE"1%"
WATTAGE"1/16W"
MATERIAL"EMPTY"
PACK_TYPE"0402LF"
$LOCATION"R701"
CDS_LIB"pure_quanta"
CDS_LOCATION"R701"
$SEC"1"
CDS_SEC"1";
"A"
$PN"1"16;
"B"
$PN"2"6;
%"UNIVERSAL_GND"
"1","(-7725,3600)","0","logical_power","I64";
;
CDS_LIB"logical_power"
HDL_POWER"GND";
"A"5;
%"Q_CAP"
"1","(-7725,3900)","2","pure_quanta","I65";
;
PART_NUMBER"CH5104KEB02"
MATERIAL"EMPTY"
TOLERANCE"10%"
VOLTAGE"25V"
VALUE"1UF"
PACK_TYPE"C0402"
$LOCATION"C614"
CDS_LIB"pure_quanta"
CDS_LOCATION"C614"
$SEC"1"
CDS_SEC"1";
"B"
$PN"2"5;
"A"
$PN"1"14;
%"Q_CAP"
"1","(-7750,-650)","2","pure_quanta","I68";
;
PART_NUMBER"CH5104KEB02"
VALUE"1UF"
VOLTAGE"25V"
TOLERANCE"10%"
PACK_TYPE"C0402"
MATERIAL"EMPTY"
$LOCATION"C613"
CDS_LIB"pure_quanta"
CDS_LOCATION"C613"
$SEC"1"
CDS_SEC"1";
"B"
$PN"2"8;
"A"
$PN"1"15;
%"Q_RES"
"2","(-7600,875)","0","pure_quanta","I75";
;
PART_NUMBER"CS31002FB08"
MATERIAL"EMPTY"
TOLERANCE"1%"
VALUE"10K"
WATTAGE"1/16W"
PACK_TYPE"0402LF"
$LOCATION"R704"
CDS_LIB"pure_quanta"
CDS_LOCATION"R704"
$SEC"1"
CDS_SEC"1";
"A"
$PN"1"10;
"B"
$PN"2"7;
%"Q_RES"
"2","(-7625,-650)","0","pure_quanta","I76";
;
PART_NUMBER"CS31002FB08"
WATTAGE"1/16W"
VALUE"10K"
PACK_TYPE"0402LF"
TOLERANCE"1%"
MATERIAL"EMPTY"
$LOCATION"R702"
CDS_LIB"pure_quanta"
CDS_LOCATION"R702"
$SEC"1"
CDS_SEC"1";
"A"
$PN"1"15;
"B"
$PN"2"8;
%"Q_RES"
"2","(-7600,3900)","0","pure_quanta","I79";
;
PART_NUMBER"CS31002FB08"
VALUE"10K"
TOLERANCE"1%"
MATERIAL"EMPTY"
PACK_TYPE"0402LF"
WATTAGE"1/16W"
$LOCATION"R703"
CDS_LIB"pure_quanta"
CDS_LOCATION"R703"
$SEC"1"
CDS_SEC"1";
"A"
$PN"1"14;
"B"
$PN"2"5;
%"UNIVERSAL_POWER"
"1","(-3175,4700)","0","logical_power","I81";
;
HDL_POWER"PVCCD_HV_CPU1"
CDS_LIB"logical_power";
"A"1;
%"Q_RES"
"2","(-3175,4450)","0","pure_quanta","I82";
;
PART_NUMBER"CS21002FB06"
TOLERANCE"1%"
VALUE"1K"
PACK_TYPE"0402LF"
WATTAGE"1/16W"
MATERIAL"CHIP"
$LOCATION"R820"
CDS_LIB"pure_quanta"
$LOCATION"R820"
CDS_LOCATION"R820"
$SEC"1"
CDS_SEC"1";
"A"
$PN"1"1;
"B"
$PN"2"11;
%"UNIVERSAL_POWER"
"1","(-3175,3175)","0","logical_power","I83";
;
HDL_POWER"PVCCD_HV_CPU1"
CDS_LIB"logical_power";
"A"4;
%"Q_RES"
"2","(-3175,2925)","0","pure_quanta","I84";
;
PART_NUMBER"CS21002FB06"
TOLERANCE"1%"
VALUE"1K"
PACK_TYPE"0402LF"
WATTAGE"1/16W"
MATERIAL"CHIP"
$LOCATION"R821"
CDS_LIB"pure_quanta"
$LOCATION"R821"
CDS_LOCATION"R821"
$SEC"1"
CDS_SEC"1";
"A"
$PN"1"4;
"B"
$PN"2"13;
%"UNIVERSAL_POWER"
"1","(-3175,1675)","0","logical_power","I87";
;
HDL_POWER"PVCCD_HV_CPU1"
CDS_LIB"logical_power";
"A"3;
%"Q_RES"
"2","(-3175,1425)","0","pure_quanta","I88";
;
PART_NUMBER"CS21002FB06"
VALUE"1K"
TOLERANCE"1%"
PACK_TYPE"0402LF"
WATTAGE"1/16W"
MATERIAL"CHIP"
$LOCATION"R822"
CDS_LIB"pure_quanta"
$LOCATION"R822"
CDS_LOCATION"R822"
$SEC"1"
CDS_SEC"1";
"A"
$PN"1"3;
"B"
$PN"2"12;
%"UNIVERSAL_POWER"
"1","(-3200,150)","0","logical_power","I89";
;
HDL_POWER"PVCCD_HV_CPU1"
CDS_LIB"logical_power";
"A"2;
%"Q_RES"
"2","(-3200,-100)","0","pure_quanta","I90";
;
PART_NUMBER"CS21002FB06"
PACK_TYPE"0402LF"
VALUE"1K"
TOLERANCE"1%"
WATTAGE"1/16W"
MATERIAL"CHIP"
$LOCATION"R819"
CDS_LIB"pure_quanta"
$LOCATION"R819"
CDS_LOCATION"R819"
$SEC"1"
CDS_SEC"1";
"A"
$PN"1"2;
"B"
$PN"2"9;
END.
